(kicad_pcb
	(version 20260206)
	(generator "pcbnew")
	(generator_version "10.0")
	(general
		(thickness 1.6)
		(legacy_teardrops no)
	)
	(paper "A4")
	(title_block
		(title "Bryce Canyon_SCC_16316-1_OCP.brd")
		(comment 1 "Bryce Canyon / footprints 1380-1386 of 1561")
	)
	(layers
		(0 "F.Cu" signal "TOP")
		(4 "In1.Cu" signal "L2GND")
		(6 "In2.Cu" signal "L3")
		(8 "In3.Cu" signal "L4VCC")
		(10 "In4.Cu" signal "L5VCC")
		(12 "In5.Cu" signal "L6")
		(14 "In6.Cu" signal "L7GND")
		(2 "B.Cu" signal "BOTTOM")
		(9 "F.Adhes" user "F.Adhesive")
		(11 "B.Adhes" user "B.Adhesive")
		(13 "F.Paste" user "Package Geometry/Pastemask Top")
		(15 "B.Paste" user "Package Geometry/Pastemask Bottom")
		(5 "F.SilkS" user "Ref Des/Silkscreen Top")
		(7 "B.SilkS" user "Ref Des/Silkscreen Bottom")
		(1 "F.Mask" user "Board Geometry/Soldermask Top")
		(3 "B.Mask" user "Board Geometry/Soldermask Bottom")
		(17 "Dwgs.User" user "User.Drawings")
		(19 "Cmts.User" user "User.Comments")
		(21 "Eco1.User" user "User.Eco1")
		(23 "Eco2.User" user "User.Eco2")
		(25 "Edge.Cuts" user "Board Geometry/Outline")
		(27 "Margin" user)
		(31 "F.CrtYd" user "Package Geometry/Place Bound Top")
		(29 "B.CrtYd" user "Package Geometry/Place Bound Bottom")
		(35 "F.Fab" user "Ref Des/Assembly Top")
		(33 "B.Fab" user "Ref Des/Assembly Bottom")
	)
	(footprint ""
		(layer "B.Cu")
		(at 178.420776 -21.15058 90)
		(property "Reference" "C324"
			(at 0 0 90)
			(layer "B.SilkS")
			(hide yes)
			(effects
				(font
					(size 1.27 1.27)
				)
				(justify mirror)
			)
		)
		(property "Value" "SCD22U10V1KX-GP"
			(at 2.8321 -1.7399 90)
			(unlocked yes)
			(layer "B.Fab")
			(hide yes)
			(effects
				(font
					(size 1.016 1.016)
					(thickness 0.1524)
				)
				(justify mirror)
			)
		)
		(property "Device Type" "C0201H13"
			(at 2.8321 -3.2639 90)
			(unlocked yes)
			(layer "B.Fab")
			(hide yes)
			(effects
				(font
					(size 1.016 1.016)
					(thickness 0.1524)
				)
				(justify mirror)
			)
		)
		(duplicate_pad_numbers_are_jumpers no)
		(fp_rect
			(start 0.2794 0.6477)
			(end -0.2794 -0.6477)
			(stroke
				(width 0)
				(type default)
			)
			(fill no)
			(layer "B.CrtYd")
		)
		(fp_rect
			(start 0.2794 0.6477)
			(end -0.2794 -0.6477)
			(stroke
				(width 0)
				(type default)
			)
			(fill no)
			(layer "B.Fab")
		)
		(pad "1" smd custom
			(at 0 -0.2794 270)
			(size 0.0762 0.0762)
			(layers "B.Cu" "B.Mask" "B.Paste")
			(net "PCIE_SCC_TO_COMP_C_6_DN")
			(options
				(clearance outline)
				(anchor circle)
			)
			(primitives
				(gr_poly
					(pts
						(arc
							(start 0.1524 0.127)
							(mid 0.137521 0.162921)
							(end 0.1016 0.1778)
						)
						(arc
							(start -0.1016 0.1778)
							(mid -0.137521 0.162921)
							(end -0.1524 0.127)
						)
						(arc
							(start -0.1524 -0.127)
							(mid -0.137521 -0.162921)
							(end -0.1016 -0.1778)
						)
						(arc
							(start 0.1016 -0.1778)
							(mid 0.137521 -0.162921)
							(end 0.1524 -0.127)
						)
					)
					(width 0)
					(fill yes)
				)
			)
		)
		(pad "2" smd custom
			(at 0 0.2794 270)
			(size 0.0762 0.0762)
			(layers "B.Cu" "B.Mask" "B.Paste")
			(net "PCIE_SCC_TO_COMP_6_DN")
			(options
				(clearance outline)
				(anchor circle)
			)
			(primitives
				(gr_poly
					(pts
						(arc
							(start 0.1524 0.127)
							(mid 0.137521 0.162921)
							(end 0.1016 0.1778)
						)
						(arc
							(start -0.1016 0.1778)
							(mid -0.137521 0.162921)
							(end -0.1524 0.127)
						)
						(arc
							(start -0.1524 -0.127)
							(mid -0.137521 -0.162921)
							(end -0.1016 -0.1778)
						)
						(arc
							(start 0.1016 -0.1778)
							(mid 0.137521 -0.162921)
							(end 0.1524 -0.127)
						)
					)
					(width 0)
					(fill yes)
				)
			)
		)
	)
	(footprint ""
		(layer "B.Cu")
		(at 127.970788 -55.499 -90)
		(property "Reference" "C302"
			(at 0 0 90)
			(layer "B.SilkS")
			(hide yes)
			(effects
				(font
					(size 1.27 1.27)
				)
				(justify mirror)
			)
		)
		(property "Value" "SC1U6D3V1MX-GP"
			(at -1.9177 2.0193 270)
			(unlocked yes)
			(layer "B.Fab")
			(hide yes)
			(effects
				(font
					(size 1.016 1.016)
					(thickness 0.1524)
				)
				(justify mirror)
			)
		)
		(property "Device Type" "C0201H14"
			(at -1.9177 0.4953 270)
			(unlocked yes)
			(layer "B.Fab")
			(hide yes)
			(effects
				(font
					(size 1.016 1.016)
					(thickness 0.1524)
				)
				(justify mirror)
			)
		)
		(duplicate_pad_numbers_are_jumpers no)
		(fp_rect
			(start 0.1524 0.3048)
			(end -0.1524 -0.3048)
			(stroke
				(width 0)
				(type default)
			)
			(fill no)
			(layer "B.CrtYd")
		)
		(fp_poly
			(pts
				(xy 0.2794 0.6477) (xy 0.2794 -0.6477) (xy -0.2794 -0.6477) (xy -0.2794 -0.1905) (xy -0.1524 -0.1905)
				(xy -0.1524 -0.3048) (xy 0.1524 -0.3048) (xy 0.1524 0.3048) (xy -0.1524 0.3048) (xy -0.1524 -0.1778)
				(xy -0.2794 -0.1778) (xy -0.2794 0.6477)
			)
			(stroke
				(width 0)
				(type default)
			)
			(fill no)
			(layer "B.CrtYd")
		)
		(fp_rect
			(start 0.2794 0.6477)
			(end -0.2794 -0.6477)
			(stroke
				(width 0)
				(type default)
			)
			(fill no)
			(layer "B.Fab")
		)
		(pad "1" smd custom
			(at 0 -0.2794 90)
			(size 0.0762 0.0762)
			(layers "B.Cu" "B.Mask" "B.Paste")
			(net "GB_VDDA")
			(options
				(clearance outline)
				(anchor circle)
			)
			(primitives
				(gr_poly
					(pts
						(arc
							(start 0.1524 0.127)
							(mid 0.137521 0.162921)
							(end 0.1016 0.1778)
						)
						(arc
							(start -0.1016 0.1778)
							(mid -0.137521 0.162921)
							(end -0.1524 0.127)
						)
						(arc
							(start -0.1524 -0.127)
							(mid -0.137521 -0.162921)
							(end -0.1016 -0.1778)
						)
						(arc
							(start 0.1016 -0.1778)
							(mid 0.137521 -0.162921)
							(end 0.1524 -0.127)
						)
					)
					(width 0)
					(fill yes)
				)
			)
		)
		(pad "2" smd custom
			(at 0 0.2794 90)
			(size 0.0762 0.0762)
			(layers "B.Cu" "B.Mask" "B.Paste")
			(net "GND")
			(options
				(clearance outline)
				(anchor circle)
			)
			(primitives
				(gr_poly
					(pts
						(arc
							(start 0.1524 0.127)
							(mid 0.137521 0.162921)
							(end 0.1016 0.1778)
						)
						(arc
							(start -0.1016 0.1778)
							(mid -0.137521 0.162921)
							(end -0.1524 0.127)
						)
						(arc
							(start -0.1524 -0.127)
							(mid -0.137521 -0.162921)
							(end -0.1016 -0.1778)
						)
						(arc
							(start 0.1016 -0.1778)
							(mid 0.137521 -0.162921)
							(end 0.1524 -0.127)
						)
					)
					(width 0)
					(fill yes)
				)
			)
		)
	)
	(footprint ""
		(layer "B.Cu")
		(at 112.9919 -61.488066)
		(property "Reference" "C223"
			(at 0 0 0)
			(layer "B.SilkS")
			(hide yes)
			(effects
				(font
					(size 1.27 1.27)
				)
				(justify mirror)
			)
		)
		(property "Value" "SCD1U16V2KX-3GP"
			(at -1.1811 -2.7051 0)
			(unlocked yes)
			(layer "B.Fab")
			(hide yes)
			(effects
				(font
					(size 1.016 1.016)
					(thickness 0.1524)
				)
				(justify mirror)
			)
		)
		(property "Device Type" "C402H22"
			(at -1.1811 -4.2291 0)
			(unlocked yes)
			(layer "B.Fab")
			(hide yes)
			(effects
				(font
					(size 1.016 1.016)
					(thickness 0.1524)
				)
				(justify mirror)
			)
		)
		(duplicate_pad_numbers_are_jumpers no)
		(fp_rect
			(start 0.4318 0.9525)
			(end -0.4318 -0.9525)
			(stroke
				(width 0)
				(type default)
			)
			(fill no)
			(layer "B.CrtYd")
		)
		(fp_rect
			(start 0.4318 0.9525)
			(end -0.4318 -0.9525)
			(stroke
				(width 0)
				(type default)
			)
			(fill no)
			(layer "B.Fab")
		)
		(pad "1" smd custom
			(at 0 -0.4445 180)
			(size 0.1524 0.1524)
			(layers "B.Cu" "B.Mask" "B.Paste")
			(net "GB_VDDH")
			(options
				(clearance outline)
				(anchor circle)
			)
			(primitives
				(gr_poly
					(pts
						(arc
							(start 0.3048 0.2032)
							(mid 0.275042 0.275042)
							(end 0.2032 0.3048)
						)
						(arc
							(start -0.2032 0.3048)
							(mid -0.275042 0.275042)
							(end -0.3048 0.2032)
						)
						(arc
							(start -0.3048 -0.2032)
							(mid -0.275042 -0.275042)
							(end -0.2032 -0.3048)
						)
						(arc
							(start 0.2032 -0.3048)
							(mid 0.275042 -0.275042)
							(end 0.3048 -0.2032)
						)
					)
					(width 0)
					(fill yes)
				)
			)
		)
		(pad "2" smd custom
			(at 0 0.4445 180)
			(size 0.1524 0.1524)
			(layers "B.Cu" "B.Mask" "B.Paste")
			(net "GND")
			(options
				(clearance outline)
				(anchor circle)
			)
			(primitives
				(gr_poly
					(pts
						(arc
							(start 0.3048 0.2032)
							(mid 0.275042 0.275042)
							(end 0.2032 0.3048)
						)
						(arc
							(start -0.2032 0.3048)
							(mid -0.275042 0.275042)
							(end -0.3048 0.2032)
						)
						(arc
							(start -0.3048 -0.2032)
							(mid -0.275042 -0.275042)
							(end -0.2032 -0.3048)
						)
						(arc
							(start 0.2032 -0.3048)
							(mid 0.275042 -0.275042)
							(end 0.3048 -0.2032)
						)
					)
					(width 0)
					(fill yes)
				)
			)
		)
	)
	(footprint ""
		(layer "B.Cu")
		(at 114.3508 -82.2706)
		(property "Reference" "R145"
			(at 0 0 0)
			(layer "B.SilkS")
			(hide yes)
			(effects
				(font
					(size 1.27 1.27)
				)
				(justify mirror)
			)
		)
		(property "Value" "4K7R2F-GP"
			(at -0.064008 -3.993896 0)
			(unlocked yes)
			(layer "B.Fab")
			(hide yes)
			(effects
				(font
					(size 1.016 1.016)
					(thickness 0.1524)
				)
				(justify mirror)
			)
		)
		(property "Device Type" "R402H16"
			(at -0.064008 -5.517896 0)
			(unlocked yes)
			(layer "B.Fab")
			(hide yes)
			(effects
				(font
					(size 1.016 1.016)
					(thickness 0.1524)
				)
				(justify mirror)
			)
		)
		(duplicate_pad_numbers_are_jumpers no)
		(fp_line
			(start -0.508 -0.9398)
			(end 0.508 -0.9398)
			(stroke
				(width 0.1524)
				(type default)
			)
			(layer "B.SilkS")
		)
		(fp_line
			(start 0.508 -0.9398)
			(end 0.508 0.9398)
			(stroke
				(width 0.1524)
				(type default)
			)
			(layer "B.SilkS")
		)
		(fp_rect
			(start 0.508 0.9398)
			(end -0.508 -0.9398)
			(stroke
				(width 0)
				(type default)
			)
			(fill no)
			(layer "B.CrtYd")
		)
		(fp_rect
			(start 0.508 0.9398)
			(end -0.508 -0.9398)
			(stroke
				(width 0)
				(type default)
			)
			(fill no)
			(layer "B.Fab")
		)
		(pad "1" smd custom
			(at 0 -0.4445 180)
			(size 0.1397 0.1397)
			(layers "B.Cu" "B.Mask" "B.Paste")
			(net "EXP_XM_ADDR_19")
			(options
				(clearance outline)
				(anchor circle)
			)
			(primitives
				(gr_poly
					(pts
						(arc
							(start -0.1778 0.2794)
							(mid -0.249642 0.249642)
							(end -0.2794 0.1778)
						)
						(arc
							(start -0.2794 -0.1778)
							(mid -0.249642 -0.249642)
							(end -0.1778 -0.2794)
						)
						(arc
							(start 0.1778 -0.2794)
							(mid 0.249642 -0.249642)
							(end 0.2794 -0.1778)
						)
						(arc
							(start 0.2794 0.1778)
							(mid 0.249642 0.249642)
							(end 0.1778 0.2794)
						)
					)
					(width 0)
					(fill yes)
				)
			)
		)
		(pad "2" smd custom
			(at 0 0.4445 180)
			(size 0.1397 0.1397)
			(layers "B.Cu" "B.Mask" "B.Paste")
			(net "GND")
			(options
				(clearance outline)
				(anchor circle)
			)
			(primitives
				(gr_poly
					(pts
						(arc
							(start -0.1778 0.2794)
							(mid -0.249642 0.249642)
							(end -0.2794 0.1778)
						)
						(arc
							(start -0.2794 -0.1778)
							(mid -0.249642 -0.249642)
							(end -0.1778 -0.2794)
						)
						(arc
							(start 0.1778 -0.2794)
							(mid 0.249642 -0.249642)
							(end 0.2794 -0.1778)
						)
						(arc
							(start 0.2794 0.1778)
							(mid 0.249642 0.249642)
							(end 0.1778 0.2794)
						)
					)
					(width 0)
					(fill yes)
				)
			)
		)
	)
	(footprint ""
		(layer "B.Cu")
		(at 127.970788 -59.491626 -90)
		(property "Reference" "C272"
			(at 0 0 90)
			(layer "B.SilkS")
			(hide yes)
			(effects
				(font
					(size 1.27 1.27)
				)
				(justify mirror)
			)
		)
		(property "Value" "SCD1U6D3V1KX-GP"
			(at 2.8321 -1.7399 270)
			(unlocked yes)
			(layer "B.Fab")
			(hide yes)
			(effects
				(font
					(size 1.016 1.016)
					(thickness 0.1524)
				)
				(justify mirror)
			)
		)
		(property "Device Type" "C0201H13"
			(at 2.8321 -3.2639 270)
			(unlocked yes)
			(layer "B.Fab")
			(hide yes)
			(effects
				(font
					(size 1.016 1.016)
					(thickness 0.1524)
				)
				(justify mirror)
			)
		)
		(duplicate_pad_numbers_are_jumpers no)
		(fp_rect
			(start 0.2794 0.6477)
			(end -0.2794 -0.6477)
			(stroke
				(width 0)
				(type default)
			)
			(fill no)
			(layer "B.CrtYd")
		)
		(fp_rect
			(start 0.2794 0.6477)
			(end -0.2794 -0.6477)
			(stroke
				(width 0)
				(type default)
			)
			(fill no)
			(layer "B.Fab")
		)
		(pad "1" smd custom
			(at 0 -0.2794 90)
			(size 0.0762 0.0762)
			(layers "B.Cu" "B.Mask" "B.Paste")
			(net "GB_VDDA")
			(options
				(clearance outline)
				(anchor circle)
			)
			(primitives
				(gr_poly
					(pts
						(arc
							(start 0.1524 0.127)
							(mid 0.137521 0.162921)
							(end 0.1016 0.1778)
						)
						(arc
							(start -0.1016 0.1778)
							(mid -0.137521 0.162921)
							(end -0.1524 0.127)
						)
						(arc
							(start -0.1524 -0.127)
							(mid -0.137521 -0.162921)
							(end -0.1016 -0.1778)
						)
						(arc
							(start 0.1016 -0.1778)
							(mid 0.137521 -0.162921)
							(end 0.1524 -0.127)
						)
					)
					(width 0)
					(fill yes)
				)
			)
		)
		(pad "2" smd custom
			(at 0 0.2794 90)
			(size 0.0762 0.0762)
			(layers "B.Cu" "B.Mask" "B.Paste")
			(net "GND")
			(options
				(clearance outline)
				(anchor circle)
			)
			(primitives
				(gr_poly
					(pts
						(arc
							(start 0.1524 0.127)
							(mid 0.137521 0.162921)
							(end 0.1016 0.1778)
						)
						(arc
							(start -0.1016 0.1778)
							(mid -0.137521 0.162921)
							(end -0.1524 0.127)
						)
						(arc
							(start -0.1524 -0.127)
							(mid -0.137521 -0.162921)
							(end -0.1016 -0.1778)
						)
						(arc
							(start 0.1016 -0.1778)
							(mid 0.137521 -0.162921)
							(end 0.1524 -0.127)
						)
					)
					(width 0)
					(fill yes)
				)
			)
		)
	)
	(footprint ""
		(layer "B.Cu")
		(at 168.530778 -47.79772)
		(property "Reference" "C464"
			(at 0 0 0)
			(layer "B.SilkS")
			(hide yes)
			(effects
				(font
					(size 1.27 1.27)
				)
				(justify mirror)
			)
		)
		(property "Value" "SCD1U6D3V1KX-GP"
			(at 2.8321 -1.7399 0)
			(unlocked yes)
			(layer "B.Fab")
			(hide yes)
			(effects
				(font
					(size 1.016 1.016)
					(thickness 0.1524)
				)
				(justify mirror)
			)
		)
		(property "Device Type" "C0201H13"
			(at 2.8321 -3.2639 0)
			(unlocked yes)
			(layer "B.Fab")
			(hide yes)
			(effects
				(font
					(size 1.016 1.016)
					(thickness 0.1524)
				)
				(justify mirror)
			)
		)
		(duplicate_pad_numbers_are_jumpers no)
		(fp_rect
			(start 0.2794 0.6477)
			(end -0.2794 -0.6477)
			(stroke
				(width 0)
				(type default)
			)
			(fill no)
			(layer "B.CrtYd")
		)
		(fp_rect
			(start 0.2794 0.6477)
			(end -0.2794 -0.6477)
			(stroke
				(width 0)
				(type default)
			)
			(fill no)
			(layer "B.Fab")
		)
		(pad "1" smd custom
			(at 0 -0.2794 180)
			(size 0.0762 0.0762)
			(layers "B.Cu" "B.Mask" "B.Paste")
			(net "P1V8_C")
			(options
				(clearance outline)
				(anchor circle)
			)
			(primitives
				(gr_poly
					(pts
						(arc
							(start 0.1524 0.127)
							(mid 0.137521 0.162921)
							(end 0.1016 0.1778)
						)
						(arc
							(start -0.1016 0.1778)
							(mid -0.137521 0.162921)
							(end -0.1524 0.127)
						)
						(arc
							(start -0.1524 -0.127)
							(mid -0.137521 -0.162921)
							(end -0.1016 -0.1778)
						)
						(arc
							(start 0.1016 -0.1778)
							(mid 0.137521 -0.162921)
							(end 0.1524 -0.127)
						)
					)
					(width 0)
					(fill yes)
				)
			)
		)
		(pad "2" smd custom
			(at 0 0.2794 180)
			(size 0.0762 0.0762)
			(layers "B.Cu" "B.Mask" "B.Paste")
			(net "GND")
			(options
				(clearance outline)
				(anchor circle)
			)
			(primitives
				(gr_poly
					(pts
						(arc
							(start 0.1524 0.127)
							(mid 0.137521 0.162921)
							(end 0.1016 0.1778)
						)
						(arc
							(start -0.1016 0.1778)
							(mid -0.137521 0.162921)
							(end -0.1524 0.127)
						)
						(arc
							(start -0.1524 -0.127)
							(mid -0.137521 -0.162921)
							(end -0.1016 -0.1778)
						)
						(arc
							(start 0.1016 -0.1778)
							(mid 0.137521 -0.162921)
							(end 0.1524 -0.127)
						)
					)
					(width 0)
					(fill yes)
				)
			)
		)
	)
	(footprint ""
		(layer "B.Cu")
		(at 126.1872 -93.5609 90)
		(property "Reference" "R350"
			(at 0 0 90)
			(layer "B.SilkS")
			(hide yes)
			(effects
				(font
					(size 1.27 1.27)
				)
				(justify mirror)
			)
		)
		(property "Value" "4K75R2F-1-GP"
			(at -0.064008 -3.993896 90)
			(unlocked yes)
			(layer "B.Fab")
			(hide yes)
			(effects
				(font
					(size 1.016 1.016)
					(thickness 0.1524)
				)
				(justify mirror)
			)
		)
		(property "Device Type" "R402H16"
			(at -0.064008 -5.517896 90)
			(unlocked yes)
			(layer "B.Fab")
			(hide yes)
			(effects
				(font
					(size 1.016 1.016)
					(thickness 0.1524)
				)
				(justify mirror)
			)
		)
		(duplicate_pad_numbers_are_jumpers no)
		(fp_line
			(start 0.508 -0.9398)
			(end 0.508 0.9398)
			(stroke
				(width 0.1524)
				(type default)
			)
			(layer "B.SilkS")
		)
		(fp_line
			(start -0.508 -0.9398)
			(end 0.508 -0.9398)
			(stroke
				(width 0.1524)
				(type default)
			)
			(layer "B.SilkS")
		)
		(fp_rect
			(start 0.508 0.9398)
			(end -0.508 -0.9398)
			(stroke
				(width 0)
				(type default)
			)
			(fill no)
			(layer "B.CrtYd")
		)
		(fp_rect
			(start 0.508 0.9398)
			(end -0.508 -0.9398)
			(stroke
				(width 0)
				(type default)
			)
			(fill no)
			(layer "B.Fab")
		)
		(pad "1" smd custom
			(at 0 -0.4445 270)
			(size 0.1397 0.1397)
			(layers "B.Cu" "B.Mask" "B.Paste")
			(net "EXP_RGMII_RXC")
			(options
				(clearance outline)
				(anchor circle)
			)
			(primitives
				(gr_poly
					(pts
						(arc
							(start -0.1778 0.2794)
							(mid -0.249642 0.249642)
							(end -0.2794 0.1778)
						)
						(arc
							(start -0.2794 -0.1778)
							(mid -0.249642 -0.249642)
							(end -0.1778 -0.2794)
						)
						(arc
							(start 0.1778 -0.2794)
							(mid 0.249642 -0.249642)
							(end 0.2794 -0.1778)
						)
						(arc
							(start 0.2794 0.1778)
							(mid 0.249642 0.249642)
							(end 0.1778 0.2794)
						)
					)
					(width 0)
					(fill yes)
				)
			)
		)
		(pad "2" smd custom
			(at 0 0.4445 270)
			(size 0.1397 0.1397)
			(layers "B.Cu" "B.Mask" "B.Paste")
			(net "GND")
			(options
				(clearance outline)
				(anchor circle)
			)
			(primitives
				(gr_poly
					(pts
						(arc
							(start -0.1778 0.2794)
							(mid -0.249642 0.249642)
							(end -0.2794 0.1778)
						)
						(arc
							(start -0.2794 -0.1778)
							(mid -0.249642 -0.249642)
							(end -0.1778 -0.2794)
						)
						(arc
							(start 0.1778 -0.2794)
							(mid 0.249642 -0.249642)
							(end 0.2794 -0.1778)
						)
						(arc
							(start 0.2794 0.1778)
							(mid 0.249642 0.249642)
							(end 0.1778 0.2794)
						)
					)
					(width 0)
					(fill yes)
				)
			)
		)
	)
)
